FILE_TYPE = MACRO_DRAWING;
SET COLOR_WIRE YELLOW;
SET COLOR_PROP ORANGE;
SET COLOR_DOT WHITE;
SET COLOR_ARC YELLOW;
SET COLOR_BODY GREEN;
SET COLOR_NOTE PURPLE;
SET PROP_DISPLAY VALUE;
SET PAGE_NUMBER P270;
FORCEADD QUANTA_TITLE_BLOCK_C..1
(5475 -1700);
FORCEPROP 1 LAST CUSTOM_TXT_CDS <NAME_2>
J 0
(2300 -1650);
FORCEPROP 1 LAST CUSTOM_TXT_CDS <NAME_1>
J 0
(2300 -1525);
FORCEPROP 1 LAST CUSTOM_TXT_CDS <Q_NUMBER>
J 0
(4072 -1597);
DISPLAY 1.212766 (4072 -1597);
FORCEPROP 1 LAST CUSTOM_TXT_CDS <Q_PROJ>
J 0
(3093 -1598);
DISPLAY 1.212766 (3093 -1598);
FORCEPROP 1 LAST CUSTOM_TXT_CDS <Q_REV>
J 0
(5291 -1597);
DISPLAY 1.212766 (5291 -1597);
FORCEPROP 1 LAST CUSTOM_TXT_CDS <CON_LAST_MODIFIED>
J 0
(3590 -1685);
DISPLAY 0.978723 (3590 -1685);
FORCEPROP 1 LAST CUSTOM_TXT_CDS <CON_PAGE_NUM> OF <CON_TOTAL_PAGES>
J 0
(5029 -1682);
DISPLAY 0.978723 (5029 -1682);
FORCEPROP 1 LAST Q_TITLE Blank
J 0
(-3891 -1674);
DISPLAY 2.446809 (-3891 -1674);
PAINT GREEN (-3891 -1674);
FORCEPROP 2 LAST PAGE_BORDER TRUE
J 0
(-2415 3550);
DISPLAY 0.638298 (-2415 3550);
PAINT PINK (-2415 3550);
DISPLAY INVISIBLE (-2415 3550);
FORCEPROP 1 LAST CDS_LMAN_SYM_OUTLINE -9475,6775,100,-125
J 0
(5475 -1700);
DISPLAY 0.468085 (5475 -1700);
PAINT GREEN (5475 -1700);
DISPLAY INVISIBLE (5475 -1700);
FORCEPROP 2 LAST CDS_LIB pure_quanta
J 0
(5475 -1700);
PAINT MONO (5475 -1700);
DISPLAY INVISIBLE (5475 -1700);
FORCEPROP 2 LAST CDS_XR_PAGE_TITLE CR-266 : @T6G_MB_LIB.T6G(SCH_1):PAGE266
J 0
(-2415 3550);
DISPLAY 0.638298 (-2415 3550);
PAINT PINK (-2415 3550);
DISPLAY INVISIBLE (-2415 3550);
FORCEPROP 2 LAST CUSTOM_TXT_CDS <XR_PAGE_TITLE>
J 0
(-2415 3550);
DISPLAY 0.638298 (-2415 3550);
PAINT PINK (-2415 3550);
DISPLAY INVISIBLE (-2415 3550);
FORCEPROP 1 LAST COMMENT_BODY TRUE
J 0
(5487 -1713);
DISPLAY 0.978723 (5487 -1713);
PAINT GREEN (5487 -1713);
DISPLAY INVISIBLE (5487 -1713);
FORCEPROP 1 LAST Q_DEPT BU9
J 1
(1712 -1651);
DISPLAY 1.957447 (1712 -1651);
PAINT GREEN (1712 -1651);
DISPLAY INVISIBLE (1712 -1651);
FORCEPROP 0 LAST CDS_CON_LAST_MODIFIED Thu Aug 24 10:15:57 2023
J 0
(3590 -1685);
PAINT MONO (3590 -1685);
DISPLAY INVISIBLE (3590 -1685);
QUIT
